# Thunderbolt PCIe Adaper — footprint library table
(fp_lib_table
  (lib (name "thunderbolt-pcie-adapter-footprints")(type "KiCad")(uri "${KIPRJMOD}/lib/thunderbolt-pcie-adapter-footprints")(options "")(descr ""))
)
